(kicad_pcb
	(version 20260206)
	(generator "pcbnew")
	(generator_version "10.0")
	(general
		(thickness 1.6)
		(legacy_teardrops no)
	)
	(paper "A4")
	(title_block
		(title "panther-plus-userver — 13130-1b_20150205.brd")
		(comment 1 "Honey Badger (Wiwynn) / footprints 903-910 of 1509")
	)
	(layers
		(0 "F.Cu" signal "TOP")
		(4 "In1.Cu" signal "L2")
		(6 "In2.Cu" signal "L3")
		(8 "In3.Cu" signal "L4")
		(10 "In4.Cu" signal "L5")
		(12 "In5.Cu" signal "L6")
		(14 "In6.Cu" signal "L7")
		(16 "In7.Cu" signal "L8")
		(18 "In8.Cu" signal "L9")
		(20 "In9.Cu" signal "L10")
		(22 "In10.Cu" signal "L11")
		(2 "B.Cu" signal "BOTTOM")
		(9 "F.Adhes" user "F.Adhesive")
		(11 "B.Adhes" user "B.Adhesive")
		(13 "F.Paste" user "Package Geometry/Pastemask Top")
		(15 "B.Paste" user "Package Geometry/Pastemask Bottom")
		(5 "F.SilkS" user "Ref Des/Silkscreen Top")
		(7 "B.SilkS" user "Ref Des/Silkscreen Bottom")
		(1 "F.Mask" user "Board Geometry/Soldermask Top")
		(3 "B.Mask" user "Board Geometry/Soldermask Bottom")
		(17 "Dwgs.User" user "User.Drawings")
		(19 "Cmts.User" user "User.Comments")
		(21 "Eco1.User" user "User.Eco1")
		(23 "Eco2.User" user "User.Eco2")
		(25 "Edge.Cuts" user "Board Geometry/Outline")
		(27 "Margin" user)
		(31 "F.CrtYd" user "Package Geometry/Place Bound Top")
		(29 "B.CrtYd" user "Package Geometry/Place Bound Bottom")
		(35 "F.Fab" user "Ref Des/Assembly Top")
		(33 "B.Fab" user "Ref Des/Assembly Bottom")
	)
	(footprint ""
		(layer "B.Cu")
		(at 46.8884 -28.321 180)
		(property "Reference" "R447"
			(at 0 0 0)
			(layer "B.SilkS")
			(hide yes)
			(effects
				(font
					(size 1.27 1.27)
				)
				(justify mirror)
			)
		)
		(property "Value" "4K7R2F-GP"
			(at -1.7907 -1.1176 180)
			(unlocked yes)
			(layer "B.Fab")
			(hide yes)
			(effects
				(font
					(size 1.016 1.016)
					(thickness 0.1524)
				)
				(justify mirror)
			)
		)
		(property "Device Type" "R402H16"
			(at -1.7907 -2.6416 180)
			(unlocked yes)
			(layer "B.Fab")
			(hide yes)
			(effects
				(font
					(size 1.016 1.016)
					(thickness 0.1524)
				)
				(justify mirror)
			)
		)
		(duplicate_pad_numbers_are_jumpers no)
		(fp_rect
			(start 0.381 0.8382)
			(end -0.381 -0.8382)
			(stroke
				(width 0)
				(type default)
			)
			(fill no)
			(layer "B.CrtYd")
		)
		(fp_rect
			(start 0.381 0.8382)
			(end -0.381 -0.8382)
			(stroke
				(width 0)
				(type default)
			)
			(fill no)
			(layer "B.Fab")
		)
		(pad "1" smd custom
			(at 0 -0.4318)
			(size 0.127 0.127)
			(layers "B.Cu" "B.Mask" "B.Paste")
			(net "CLKBUFF_OE6#")
			(options
				(clearance outline)
				(anchor circle)
			)
			(primitives
				(gr_poly
					(pts
						(arc
							(start -0.2032 0.2794)
							(mid -0.239121 0.264521)
							(end -0.254 0.2286)
						)
						(arc
							(start -0.254 -0.2286)
							(mid -0.239121 -0.264521)
							(end -0.2032 -0.2794)
						)
						(arc
							(start 0.2032 -0.2794)
							(mid 0.239121 -0.264521)
							(end 0.254 -0.2286)
						)
						(arc
							(start 0.254 0.2286)
							(mid 0.239121 0.264521)
							(end 0.2032 0.2794)
						)
					)
					(width 0)
					(fill yes)
				)
			)
		)
		(pad "2" smd custom
			(at 0 0.4318)
			(size 0.127 0.127)
			(layers "B.Cu" "B.Mask" "B.Paste")
			(net "GND")
			(options
				(clearance outline)
				(anchor circle)
			)
			(primitives
				(gr_poly
					(pts
						(arc
							(start -0.2032 0.2794)
							(mid -0.239121 0.264521)
							(end -0.254 0.2286)
						)
						(arc
							(start -0.254 -0.2286)
							(mid -0.239121 -0.264521)
							(end -0.2032 -0.2794)
						)
						(arc
							(start 0.2032 -0.2794)
							(mid 0.239121 -0.264521)
							(end 0.254 -0.2286)
						)
						(arc
							(start 0.254 0.2286)
							(mid 0.239121 0.264521)
							(end 0.2032 0.2794)
						)
					)
					(width 0)
					(fill yes)
				)
			)
		)
	)
	(footprint ""
		(layer "B.Cu")
		(at 86.106 -20.701 -90)
		(property "Reference" "PR224"
			(at 0 0 90)
			(layer "B.SilkS")
			(hide yes)
			(effects
				(font
					(size 1.27 1.27)
				)
				(justify mirror)
			)
		)
		(property "Value" "3K3R2F-2-GP"
			(at -0.064008 -3.993896 270)
			(unlocked yes)
			(layer "B.Fab")
			(hide yes)
			(effects
				(font
					(size 1.016 1.016)
					(thickness 0.1524)
				)
				(justify mirror)
			)
		)
		(property "Device Type" "R402H16"
			(at -0.064008 -5.517896 270)
			(unlocked yes)
			(layer "B.Fab")
			(hide yes)
			(effects
				(font
					(size 1.016 1.016)
					(thickness 0.1524)
				)
				(justify mirror)
			)
		)
		(duplicate_pad_numbers_are_jumpers no)
		(fp_rect
			(start 0.381 0.8382)
			(end -0.381 -0.8382)
			(stroke
				(width 0)
				(type default)
			)
			(fill no)
			(layer "B.CrtYd")
		)
		(fp_rect
			(start 0.381 0.8382)
			(end -0.381 -0.8382)
			(stroke
				(width 0)
				(type default)
			)
			(fill no)
			(layer "B.Fab")
		)
		(pad "1" smd custom
			(at 0 -0.4318 90)
			(size 0.127 0.127)
			(layers "B.Cu" "B.Mask" "B.Paste")
			(net "TPS74801_1V35_OUT")
			(options
				(clearance outline)
				(anchor circle)
			)
			(primitives
				(gr_poly
					(pts
						(arc
							(start -0.2032 0.2794)
							(mid -0.239121 0.264521)
							(end -0.254 0.2286)
						)
						(arc
							(start -0.254 -0.2286)
							(mid -0.239121 -0.264521)
							(end -0.2032 -0.2794)
						)
						(arc
							(start 0.2032 -0.2794)
							(mid 0.239121 -0.264521)
							(end 0.254 -0.2286)
						)
						(arc
							(start 0.254 0.2286)
							(mid 0.239121 0.264521)
							(end 0.2032 0.2794)
						)
					)
					(width 0)
					(fill yes)
				)
			)
		)
		(pad "2" smd custom
			(at 0 0.4318 90)
			(size 0.127 0.127)
			(layers "B.Cu" "B.Mask" "B.Paste")
			(net "TPS74801_1V35_FB")
			(options
				(clearance outline)
				(anchor circle)
			)
			(primitives
				(gr_poly
					(pts
						(arc
							(start -0.2032 0.2794)
							(mid -0.239121 0.264521)
							(end -0.254 0.2286)
						)
						(arc
							(start -0.254 -0.2286)
							(mid -0.239121 -0.264521)
							(end -0.2032 -0.2794)
						)
						(arc
							(start 0.2032 -0.2794)
							(mid 0.239121 -0.264521)
							(end 0.254 -0.2286)
						)
						(arc
							(start 0.254 0.2286)
							(mid 0.239121 0.264521)
							(end 0.2032 0.2794)
						)
					)
					(width 0)
					(fill yes)
				)
			)
		)
	)
	(footprint ""
		(layer "B.Cu")
		(at 75.565 -36.703 180)
		(property "Reference" "R376"
			(at 0 0 0)
			(layer "B.SilkS")
			(hide yes)
			(effects
				(font
					(size 1.27 1.27)
				)
				(justify mirror)
			)
		)
		(property "Value" "33R2F-3-GP"
			(at -0.064008 -3.993896 180)
			(unlocked yes)
			(layer "B.Fab")
			(hide yes)
			(effects
				(font
					(size 1.016 1.016)
					(thickness 0.1524)
				)
				(justify mirror)
			)
		)
		(property "Device Type" "R402H16"
			(at -0.064008 -5.517896 180)
			(unlocked yes)
			(layer "B.Fab")
			(hide yes)
			(effects
				(font
					(size 1.016 1.016)
					(thickness 0.1524)
				)
				(justify mirror)
			)
		)
		(duplicate_pad_numbers_are_jumpers no)
		(fp_rect
			(start 0.381 0.8382)
			(end -0.381 -0.8382)
			(stroke
				(width 0)
				(type default)
			)
			(fill no)
			(layer "B.CrtYd")
		)
		(fp_rect
			(start 0.381 0.8382)
			(end -0.381 -0.8382)
			(stroke
				(width 0)
				(type default)
			)
			(fill no)
			(layer "B.Fab")
		)
		(pad "1" smd custom
			(at 0 -0.4318)
			(size 0.127 0.127)
			(layers "B.Cu" "B.Mask" "B.Paste")
			(net "LPC_CPU_CLKOUT0")
			(options
				(clearance outline)
				(anchor circle)
			)
			(primitives
				(gr_poly
					(pts
						(arc
							(start -0.2032 0.2794)
							(mid -0.239121 0.264521)
							(end -0.254 0.2286)
						)
						(arc
							(start -0.254 -0.2286)
							(mid -0.239121 -0.264521)
							(end -0.2032 -0.2794)
						)
						(arc
							(start 0.2032 -0.2794)
							(mid 0.239121 -0.264521)
							(end 0.254 -0.2286)
						)
						(arc
							(start 0.254 0.2286)
							(mid 0.239121 0.264521)
							(end 0.2032 0.2794)
						)
					)
					(width 0)
					(fill yes)
				)
			)
		)
		(pad "2" smd custom
			(at 0 0.4318)
			(size 0.127 0.127)
			(layers "B.Cu" "B.Mask" "B.Paste")
			(net "LPC_CPU_R_CLKOUT0")
			(options
				(clearance outline)
				(anchor circle)
			)
			(primitives
				(gr_poly
					(pts
						(arc
							(start -0.2032 0.2794)
							(mid -0.239121 0.264521)
							(end -0.254 0.2286)
						)
						(arc
							(start -0.254 -0.2286)
							(mid -0.239121 -0.264521)
							(end -0.2032 -0.2794)
						)
						(arc
							(start 0.2032 -0.2794)
							(mid 0.239121 -0.264521)
							(end 0.254 -0.2286)
						)
						(arc
							(start 0.254 0.2286)
							(mid 0.239121 0.264521)
							(end 0.2032 0.2794)
						)
					)
					(width 0)
					(fill yes)
				)
			)
		)
	)
	(footprint ""
		(layer "B.Cu")
		(at 112.014 -35.941)
		(property "Reference" "C195"
			(at 0 0 0)
			(layer "B.SilkS")
			(hide yes)
			(effects
				(font
					(size 1.27 1.27)
				)
				(justify mirror)
			)
		)
		(property "Value" "SC1U10V2KX-1GP"
			(at -1.1811 -2.7051 0)
			(unlocked yes)
			(layer "B.Fab")
			(hide yes)
			(effects
				(font
					(size 1.016 1.016)
					(thickness 0.1524)
				)
				(justify mirror)
			)
		)
		(property "Device Type" "C402H22"
			(at -1.1811 -4.2291 0)
			(unlocked yes)
			(layer "B.Fab")
			(hide yes)
			(effects
				(font
					(size 1.016 1.016)
					(thickness 0.1524)
				)
				(justify mirror)
			)
		)
		(duplicate_pad_numbers_are_jumpers no)
		(fp_rect
			(start 0.381 0.7366)
			(end -0.381 -0.7366)
			(stroke
				(width 0)
				(type default)
			)
			(fill no)
			(layer "B.CrtYd")
		)
		(fp_rect
			(start 0.381 0.7366)
			(end -0.381 -0.7366)
			(stroke
				(width 0)
				(type default)
			)
			(fill no)
			(layer "B.Fab")
		)
		(pad "1" smd custom
			(at 0 -0.4572 180)
			(size 0.1143 0.1143)
			(layers "B.Cu" "B.Mask" "B.Paste")
			(net "PVCCP")
			(options
				(clearance outline)
				(anchor circle)
			)
			(primitives
				(gr_poly
					(pts
						(arc
							(start -0.254 0.1778)
							(mid -0.239121 0.213721)
							(end -0.2032 0.2286)
						)
						(arc
							(start 0.2032 0.2286)
							(mid 0.239121 0.213721)
							(end 0.254 0.1778)
						)
						(arc
							(start 0.254 -0.1778)
							(mid 0.239121 -0.213721)
							(end 0.2032 -0.2286)
						)
						(arc
							(start -0.2032 -0.2286)
							(mid -0.239121 -0.213721)
							(end -0.254 -0.1778)
						)
					)
					(width 0)
					(fill yes)
				)
			)
		)
		(pad "2" smd custom
			(at 0 0.4572 180)
			(size 0.1143 0.1143)
			(layers "B.Cu" "B.Mask" "B.Paste")
			(net "GND")
			(options
				(clearance outline)
				(anchor circle)
			)
			(primitives
				(gr_poly
					(pts
						(arc
							(start -0.254 0.1778)
							(mid -0.239121 0.213721)
							(end -0.2032 0.2286)
						)
						(arc
							(start 0.2032 0.2286)
							(mid 0.239121 0.213721)
							(end 0.254 0.1778)
						)
						(arc
							(start 0.254 -0.1778)
							(mid 0.239121 -0.213721)
							(end 0.2032 -0.2286)
						)
						(arc
							(start -0.2032 -0.2286)
							(mid -0.239121 -0.213721)
							(end -0.254 -0.1778)
						)
					)
					(width 0)
					(fill yes)
				)
			)
		)
	)
	(footprint ""
		(layer "B.Cu")
		(at 155.7528 -59.5884)
		(property "Reference" "C101"
			(at 0 0 0)
			(layer "B.SilkS")
			(hide yes)
			(effects
				(font
					(size 1.27 1.27)
				)
				(justify mirror)
			)
		)
		(property "Value" "SC1U10V2KX-1GP"
			(at -1.8923 -1.2065 0)
			(unlocked yes)
			(layer "B.Fab")
			(hide yes)
			(effects
				(font
					(size 1.016 1.016)
					(thickness 0.1524)
				)
				(justify mirror)
			)
		)
		(property "Device Type" "C402H22"
			(at -1.8923 -2.7305 0)
			(unlocked yes)
			(layer "B.Fab")
			(hide yes)
			(effects
				(font
					(size 1.016 1.016)
					(thickness 0.1524)
				)
				(justify mirror)
			)
		)
		(duplicate_pad_numbers_are_jumpers no)
		(fp_rect
			(start 0.381 0.7366)
			(end -0.381 -0.7366)
			(stroke
				(width 0)
				(type default)
			)
			(fill no)
			(layer "B.CrtYd")
		)
		(fp_rect
			(start 0.381 0.7366)
			(end -0.381 -0.7366)
			(stroke
				(width 0)
				(type default)
			)
			(fill no)
			(layer "B.Fab")
		)
		(pad "1" smd custom
			(at 0 -0.4572 180)
			(size 0.1143 0.1143)
			(layers "B.Cu" "B.Mask" "B.Paste")
			(net "PV_VDDR")
			(options
				(clearance outline)
				(anchor circle)
			)
			(primitives
				(gr_poly
					(pts
						(arc
							(start -0.254 0.1778)
							(mid -0.239121 0.213721)
							(end -0.2032 0.2286)
						)
						(arc
							(start 0.2032 0.2286)
							(mid 0.239121 0.213721)
							(end 0.254 0.1778)
						)
						(arc
							(start 0.254 -0.1778)
							(mid 0.239121 -0.213721)
							(end 0.2032 -0.2286)
						)
						(arc
							(start -0.2032 -0.2286)
							(mid -0.239121 -0.213721)
							(end -0.254 -0.1778)
						)
					)
					(width 0)
					(fill yes)
				)
			)
		)
		(pad "2" smd custom
			(at 0 0.4572 180)
			(size 0.1143 0.1143)
			(layers "B.Cu" "B.Mask" "B.Paste")
			(net "GND")
			(options
				(clearance outline)
				(anchor circle)
			)
			(primitives
				(gr_poly
					(pts
						(arc
							(start -0.254 0.1778)
							(mid -0.239121 0.213721)
							(end -0.2032 0.2286)
						)
						(arc
							(start 0.2032 0.2286)
							(mid 0.239121 0.213721)
							(end 0.254 0.1778)
						)
						(arc
							(start 0.254 -0.1778)
							(mid 0.239121 -0.213721)
							(end 0.2032 -0.2286)
						)
						(arc
							(start -0.2032 -0.2286)
							(mid -0.239121 -0.213721)
							(end -0.254 -0.1778)
						)
					)
					(width 0)
					(fill yes)
				)
			)
		)
	)
	(footprint ""
		(layer "B.Cu")
		(at 199.300084 -71.300086 -90)
		(property "Reference" "LED1"
			(at 0 0 90)
			(layer "B.SilkS")
			(hide yes)
			(effects
				(font
					(size 1.27 1.27)
				)
				(justify mirror)
			)
		)
		(property "Value" "LED-B-36-GP"
			(at 0.0635 -2.4765 270)
			(unlocked yes)
			(layer "B.Fab")
			(hide yes)
			(effects
				(font
					(size 1.016 1.016)
					(thickness 0.1524)
				)
				(justify mirror)
			)
		)
		(property "Device Type" "LED1608-1H32"
			(at 0.0635 -4.0005 270)
			(unlocked yes)
			(layer "B.Fab")
			(hide yes)
			(effects
				(font
					(size 1.016 1.016)
					(thickness 0.1524)
				)
				(justify mirror)
			)
		)
		(duplicate_pad_numbers_are_jumpers no)
		(fp_line
			(start 0.5969 -1.3081)
			(end -0.5842 -1.3081)
			(stroke
				(width 0.254)
				(type default)
			)
			(layer "B.SilkS")
		)
		(fp_rect
			(start 0.635 1.1811)
			(end -0.635 -1.1811)
			(stroke
				(width 0)
				(type default)
			)
			(fill no)
			(layer "B.CrtYd")
		)
		(fp_rect
			(start 0.635 1.1811)
			(end -0.635 -1.1811)
			(stroke
				(width 0)
				(type default)
			)
			(fill no)
			(layer "B.Fab")
		)
		(pad "1" smd custom
			(at 0 0.762 90)
			(size 0.19685 0.19685)
			(layers "B.Cu" "B.Mask" "B.Paste")
			(net "PWR_STATUS_LED")
			(options
				(clearance outline)
				(anchor circle)
			)
			(primitives
				(gr_poly
					(pts
						(arc
							(start 0.508 0.2921)
							(mid 0.478242 0.363942)
							(end 0.4064 0.3937)
						)
						(arc
							(start -0.4064 0.3937)
							(mid -0.478242 0.363942)
							(end -0.508 0.2921)
						)
						(arc
							(start -0.508 -0.2921)
							(mid -0.478242 -0.363942)
							(end -0.4064 -0.3937)
						)
						(arc
							(start 0.4064 -0.3937)
							(mid 0.478242 -0.363942)
							(end 0.508 -0.2921)
						)
					)
					(width 0)
					(fill yes)
				)
			)
		)
		(pad "2" smd custom
			(at 0 -0.762 90)
			(size 0.19685 0.19685)
			(layers "B.Cu" "B.Mask" "B.Paste")
			(net "PWR_STATUS_LED_D")
			(options
				(clearance outline)
				(anchor circle)
			)
			(primitives
				(gr_poly
					(pts
						(arc
							(start 0.508 0.2921)
							(mid 0.478242 0.363942)
							(end 0.4064 0.3937)
						)
						(arc
							(start -0.4064 0.3937)
							(mid -0.478242 0.363942)
							(end -0.508 0.2921)
						)
						(arc
							(start -0.508 -0.2921)
							(mid -0.478242 -0.363942)
							(end -0.4064 -0.3937)
						)
						(arc
							(start 0.4064 -0.3937)
							(mid 0.478242 -0.363942)
							(end 0.508 -0.2921)
						)
					)
					(width 0)
					(fill yes)
				)
			)
		)
	)
	(footprint ""
		(layer "B.Cu")
		(at 15.621 -48.133)
		(property "Reference" "C249"
			(at 0 0 0)
			(layer "B.SilkS")
			(hide yes)
			(effects
				(font
					(size 1.27 1.27)
				)
				(justify mirror)
			)
		)
		(property "Value" "SCD1U16V2KX-3GP"
			(at -1.8923 -1.2065 0)
			(unlocked yes)
			(layer "B.Fab")
			(hide yes)
			(effects
				(font
					(size 1.016 1.016)
					(thickness 0.1524)
				)
				(justify mirror)
			)
		)
		(property "Device Type" "C402H22"
			(at -1.8923 -2.7305 0)
			(unlocked yes)
			(layer "B.Fab")
			(hide yes)
			(effects
				(font
					(size 1.016 1.016)
					(thickness 0.1524)
				)
				(justify mirror)
			)
		)
		(duplicate_pad_numbers_are_jumpers no)
		(fp_rect
			(start 0.381 0.7366)
			(end -0.381 -0.7366)
			(stroke
				(width 0)
				(type default)
			)
			(fill no)
			(layer "B.CrtYd")
		)
		(fp_rect
			(start 0.381 0.7366)
			(end -0.381 -0.7366)
			(stroke
				(width 0)
				(type default)
			)
			(fill no)
			(layer "B.Fab")
		)
		(pad "1" smd custom
			(at 0 -0.4572 180)
			(size 0.1143 0.1143)
			(layers "B.Cu" "B.Mask" "B.Paste")
			(net "P3V3")
			(options
				(clearance outline)
				(anchor circle)
			)
			(primitives
				(gr_poly
					(pts
						(arc
							(start -0.254 0.1778)
							(mid -0.239121 0.213721)
							(end -0.2032 0.2286)
						)
						(arc
							(start 0.2032 0.2286)
							(mid 0.239121 0.213721)
							(end 0.254 0.1778)
						)
						(arc
							(start 0.254 -0.1778)
							(mid 0.239121 -0.213721)
							(end 0.2032 -0.2286)
						)
						(arc
							(start -0.2032 -0.2286)
							(mid -0.239121 -0.213721)
							(end -0.254 -0.1778)
						)
					)
					(width 0)
					(fill yes)
				)
			)
		)
		(pad "2" smd custom
			(at 0 0.4572 180)
			(size 0.1143 0.1143)
			(layers "B.Cu" "B.Mask" "B.Paste")
			(net "GND")
			(options
				(clearance outline)
				(anchor circle)
			)
			(primitives
				(gr_poly
					(pts
						(arc
							(start -0.254 0.1778)
							(mid -0.239121 0.213721)
							(end -0.2032 0.2286)
						)
						(arc
							(start 0.2032 0.2286)
							(mid 0.239121 0.213721)
							(end 0.254 0.1778)
						)
						(arc
							(start 0.254 -0.1778)
							(mid 0.239121 -0.213721)
							(end 0.2032 -0.2286)
						)
						(arc
							(start -0.2032 -0.2286)
							(mid -0.239121 -0.213721)
							(end -0.254 -0.1778)
						)
					)
					(width 0)
					(fill yes)
				)
			)
		)
	)
	(footprint ""
		(layer "B.Cu")
		(at 95.19412 -46.89094 90)
		(property "Reference" "C147"
			(at 0 0 90)
			(layer "B.SilkS")
			(hide yes)
			(effects
				(font
					(size 1.27 1.27)
				)
				(justify mirror)
			)
		)
		(property "Value" "SC1U10V2KX-1GP"
			(at -1.1811 -2.7051 90)
			(unlocked yes)
			(layer "B.Fab")
			(hide yes)
			(effects
				(font
					(size 1.016 1.016)
					(thickness 0.1524)
				)
				(justify mirror)
			)
		)
		(property "Device Type" "C402H22"
			(at -1.1811 -4.2291 90)
			(unlocked yes)
			(layer "B.Fab")
			(hide yes)
			(effects
				(font
					(size 1.016 1.016)
					(thickness 0.1524)
				)
				(justify mirror)
			)
		)
		(duplicate_pad_numbers_are_jumpers no)
		(fp_rect
			(start 0.381 0.7366)
			(end -0.381 -0.7366)
			(stroke
				(width 0)
				(type default)
			)
			(fill no)
			(layer "B.CrtYd")
		)
		(fp_rect
			(start 0.381 0.7366)
			(end -0.381 -0.7366)
			(stroke
				(width 0)
				(type default)
			)
			(fill no)
			(layer "B.Fab")
		)
		(pad "1" smd custom
			(at 0 -0.4572 270)
			(size 0.1143 0.1143)
			(layers "B.Cu" "B.Mask" "B.Paste")
			(net "P1V0")
			(options
				(clearance outline)
				(anchor circle)
			)
			(primitives
				(gr_poly
					(pts
						(arc
							(start -0.254 0.1778)
							(mid -0.239121 0.213721)
							(end -0.2032 0.2286)
						)
						(arc
							(start 0.2032 0.2286)
							(mid 0.239121 0.213721)
							(end 0.254 0.1778)
						)
						(arc
							(start 0.254 -0.1778)
							(mid 0.239121 -0.213721)
							(end 0.2032 -0.2286)
						)
						(arc
							(start -0.2032 -0.2286)
							(mid -0.239121 -0.213721)
							(end -0.254 -0.1778)
						)
					)
					(width 0)
					(fill yes)
				)
			)
		)
		(pad "2" smd custom
			(at 0 0.4572 270)
			(size 0.1143 0.1143)
			(layers "B.Cu" "B.Mask" "B.Paste")
			(net "GND")
			(options
				(clearance outline)
				(anchor circle)
			)
			(primitives
				(gr_poly
					(pts
						(arc
							(start -0.254 0.1778)
							(mid -0.239121 0.213721)
							(end -0.2032 0.2286)
						)
						(arc
							(start 0.2032 0.2286)
							(mid 0.239121 0.213721)
							(end 0.254 0.1778)
						)
						(arc
							(start 0.254 -0.1778)
							(mid 0.239121 -0.213721)
							(end 0.2032 -0.2286)
						)
						(arc
							(start -0.2032 -0.2286)
							(mid -0.239121 -0.213721)
							(end -0.254 -0.1778)
						)
					)
					(width 0)
					(fill yes)
				)
			)
		)
	)
)
